(kicad_pcb
	(version 20241229)
	(generator "pcbnew")
	(generator_version "9.0")
	(general
		(thickness 1.62)
		(legacy_teardrops no)
	)
	(paper "A3")
	(title_block
		(title "COM Express 7 Baseboard")
		(date "2025-02-04")
		(rev "1.1.2")
		(company "Antmicro Ltd")
		(comment 1 "www.antmicro.com")
		(comment 9 "footprints 179-182 of 802")
	)
	(layers
		(0 "F.Cu" signal)
		(4 "In1.Cu" signal)
		(6 "In2.Cu" signal)
		(8 "In3.Cu" signal)
		(10 "In4.Cu" signal)
		(12 "In5.Cu" signal)
		(14 "In6.Cu" signal)
		(2 "B.Cu" signal)
		(9 "F.Adhes" user "F.Adhesive")
		(11 "B.Adhes" user "B.Adhesive")
		(13 "F.Paste" user)
		(15 "B.Paste" user)
		(5 "F.SilkS" user "F.Silkscreen")
		(7 "B.SilkS" user "B.Silkscreen")
		(1 "F.Mask" user)
		(3 "B.Mask" user)
		(17 "Dwgs.User" user "User.Drawings")
		(19 "Cmts.User" user "User.Comments")
		(21 "Eco1.User" user "User.Eco1")
		(23 "Eco2.User" user "User.Eco2")
		(25 "Edge.Cuts" user)
		(27 "Margin" user)
		(31 "F.CrtYd" user "F.Courtyard")
		(29 "B.CrtYd" user "B.Courtyard")
		(35 "F.Fab" user)
		(33 "B.Fab" user)
	)
	(footprint "antmicro-footprints:Spacer_Drill3.7mm_H5mm_9774050151R"
		(layer "F.Cu")
		(at 278.93 167.8 90)
		(descr "Spacer M=3 h=5mm fi=5.1mm")
		(property "Reference" "H10"
			(at -1.19 -3.43 90)
			(layer "F.SilkS")
			(hide yes)
			(effects
				(font
					(size 0.7 0.7)
					(thickness 0.15)
				)
				(justify left bottom)
			)
		)
		(property "Value" "Spacer_Drill3.7mm_H5mm_9774050151R"
			(at 0 4 90)
			(layer "F.Fab")
			(effects
				(font
					(size 0.7 0.7)
					(thickness 0.15)
				)
				(justify left bottom)
			)
		)
		(property "Datasheet" "https://www.we-online.com/catalog/datasheet/9774050151.pdf"
			(at 0 0 90)
			(layer "F.Fab")
			(hide yes)
			(effects
				(font
					(size 1.27 1.27)
					(thickness 0.15)
				)
			)
		)
		(property "Author" "Antmicro"
			(at 446.74 -111.12 0)
			(layer "F.Fab")
			(hide yes)
			(effects
				(font
					(size 1 1)
					(thickness 0.15)
				)
			)
		)
		(property "License" "Apache-2.0"
			(at 446.74 -111.12 0)
			(layer "F.Fab")
			(hide yes)
			(effects
				(font
					(size 1 1)
					(thickness 0.15)
				)
			)
		)
		(property "MPN" "9774050151R"
			(at 446.74 -111.12 0)
			(layer "F.Fab")
			(hide yes)
			(effects
				(font
					(size 1 1)
					(thickness 0.15)
				)
			)
		)
		(property "Manufacturer" "Würth Elektronik"
			(at 446.74 -111.12 0)
			(layer "F.Fab")
			(hide yes)
			(effects
				(font
					(size 1 1)
					(thickness 0.15)
				)
			)
		)
		(sheetname "Com Express 7 Interfaces")
		(sheetfile "com_express_7_interfaces.kicad_sch")
		(solder_paste_margin_ratio -1)
		(attr smd)
		(fp_circle
			(center 0 0)
			(end 3.05 0)
			(stroke
				(width 0.05)
				(type solid)
			)
			(fill no)
			(layer "F.CrtYd")
		)
		(fp_circle
			(center 0 0)
			(end 2.6 0)
			(stroke
				(width 0.15)
				(type solid)
			)
			(fill no)
			(layer "F.Fab")
		)
		(pad "" smd custom
			(at -1.7 -1.7 90)
			(size 0.62 0.62)
			(layers "F.Paste")
			(thermal_bridge_angle 90)
			(options
				(clearance outline)
				(anchor circle)
			)
			(primitives
				(gr_arc
					(start -0.250195 1.279127)
					(mid 0.285453 0.294389)
					(end 1.266786 -0.24747)
					(width 0.2)
				)
				(gr_arc
					(start -0.34334 1.279127)
					(mid 0.218448 0.232561)
					(end 1.259603 -0.339191)
					(width 0.2)
				)
				(gr_arc
					(start -0.436309 1.279127)
					(mid 0.152481 0.169693)
					(end 1.255279 -0.431435)
					(width 0.2)
				)
				(gr_arc
					(start -0.529126 1.279127)
					(mid 0.087542 0.105784)
					(end 1.253811 -0.524161)
					(width 0.2)
				)
				(gr_arc
					(start -0.621807 1.279127)
					(mid 0.0309 0.033527)
					(end 1.275473 -0.621136)
					(width 0.2)
				)
				(gr_arc
					(start -0.71437 1.279127)
					(mid -0.037758 -0.026651)
					(end 1.263664 -0.711602)
					(width 0.2)
				)
				(gr_arc
					(start -0.806826 1.279127)
					(mid -0.105837 -0.087395)
					(end 1.253435 -0.802342)
					(width 0.2)
				)
				(gr_arc
					(start -0.899187 1.279127)
					(mid -0.165236 -0.156885)
					(end 1.267475 -0.897258)
					(width 0.2)
				)
				(gr_arc
					(start -0.991463 1.279127)
					(mid -0.228522 -0.222449)
					(end 1.270645 -0.990112)
					(width 0.2)
				)
				(gr_arc
					(start -1.083663 1.279127)
					(mid -0.294507 -0.285313)
					(end 1.266278 -1.081674)
					(width 0.2)
				)
				(gr_line
					(start 1.279127 -0.250195)
					(end 1.279127 -1.083663)
					(width 0.2)
				)
				(gr_line
					(start -0.250195 1.279127)
					(end -1.083663 1.279127)
					(width 0.2)
				)
			)
			(teardrops
				(best_length_ratio 0.2)
				(max_length 1)
				(best_width_ratio 0.9)
				(max_width 2)
				(curved_edges yes)
				(filter_ratio 0.9)
				(enabled yes)
				(allow_two_segments yes)
				(prefer_zone_connections yes)
			)
		)
		(pad "" smd custom
			(at -1.7 1.7 180)
			(size 0.62 0.62)
			(layers "F.Paste")
			(thermal_bridge_angle 90)
			(options
				(clearance outline)
				(anchor circle)
			)
			(primitives
				(gr_arc
					(start -0.250195 1.279127)
					(mid 0.285453 0.294389)
					(end 1.266786 -0.24747)
					(width 0.2)
				)
				(gr_arc
					(start -0.34334 1.279127)
					(mid 0.218448 0.232561)
					(end 1.259603 -0.339191)
					(width 0.2)
				)
				(gr_arc
					(start -0.436309 1.279127)
					(mid 0.152481 0.169693)
					(end 1.255279 -0.431435)
					(width 0.2)
				)
				(gr_arc
					(start -0.529126 1.279127)
					(mid 0.087542 0.105784)
					(end 1.253811 -0.524161)
					(width 0.2)
				)
				(gr_arc
					(start -0.621807 1.279127)
					(mid 0.0309 0.033527)
					(end 1.275473 -0.621136)
					(width 0.2)
				)
				(gr_arc
					(start -0.71437 1.279127)
					(mid -0.037758 -0.026651)
					(end 1.263664 -0.711602)
					(width 0.2)
				)
				(gr_arc
					(start -0.806826 1.279127)
					(mid -0.105837 -0.087395)
					(end 1.253435 -0.802342)
					(width 0.2)
				)
				(gr_arc
					(start -0.899187 1.279127)
					(mid -0.165236 -0.156885)
					(end 1.267475 -0.897258)
					(width 0.2)
				)
				(gr_arc
					(start -0.991463 1.279127)
					(mid -0.228522 -0.222449)
					(end 1.270645 -0.990112)
					(width 0.2)
				)
				(gr_arc
					(start -1.083663 1.279127)
					(mid -0.294507 -0.285313)
					(end 1.266278 -1.081674)
					(width 0.2)
				)
				(gr_line
					(start 1.279127 -0.250195)
					(end 1.279127 -1.083663)
					(width 0.2)
				)
				(gr_line
					(start -0.250195 1.279127)
					(end -1.083663 1.279127)
					(width 0.2)
				)
			)
			(teardrops
				(best_length_ratio 0.2)
				(max_length 1)
				(best_width_ratio 0.9)
				(max_width 2)
				(curved_edges yes)
				(filter_ratio 0.9)
				(enabled yes)
				(allow_two_segments yes)
				(prefer_zone_connections yes)
			)
		)
		(pad "" smd custom
			(at 1.7 -1.7)
			(size 0.62 0.62)
			(layers "F.Paste")
			(thermal_bridge_angle 90)
			(options
				(clearance outline)
				(anchor circle)
			)
			(primitives
				(gr_arc
					(start -0.250195 1.279127)
					(mid 0.285453 0.294389)
					(end 1.266786 -0.24747)
					(width 0.2)
				)
				(gr_arc
					(start -0.34334 1.279127)
					(mid 0.218448 0.232561)
					(end 1.259603 -0.339191)
					(width 0.2)
				)
				(gr_arc
					(start -0.436309 1.279127)
					(mid 0.152481 0.169693)
					(end 1.255279 -0.431435)
					(width 0.2)
				)
				(gr_arc
					(start -0.529126 1.279127)
					(mid 0.087542 0.105784)
					(end 1.253811 -0.524161)
					(width 0.2)
				)
				(gr_arc
					(start -0.621807 1.279127)
					(mid 0.0309 0.033527)
					(end 1.275473 -0.621136)
					(width 0.2)
				)
				(gr_arc
					(start -0.71437 1.279127)
					(mid -0.037758 -0.026651)
					(end 1.263664 -0.711602)
					(width 0.2)
				)
				(gr_arc
					(start -0.806826 1.279127)
					(mid -0.105837 -0.087395)
					(end 1.253435 -0.802342)
					(width 0.2)
				)
				(gr_arc
					(start -0.899187 1.279127)
					(mid -0.165236 -0.156885)
					(end 1.267475 -0.897258)
					(width 0.2)
				)
				(gr_arc
					(start -0.991463 1.279127)
					(mid -0.228522 -0.222449)
					(end 1.270645 -0.990112)
					(width 0.2)
				)
				(gr_arc
					(start -1.083663 1.279127)
					(mid -0.294507 -0.285313)
					(end 1.266278 -1.081674)
					(width 0.2)
				)
				(gr_line
					(start 1.279127 -0.250195)
					(end 1.279127 -1.083663)
					(width 0.2)
				)
				(gr_line
					(start -0.250195 1.279127)
					(end -1.083663 1.279127)
					(width 0.2)
				)
			)
			(teardrops
				(best_length_ratio 0.2)
				(max_length 1)
				(best_width_ratio 0.9)
				(max_width 2)
				(curved_edges yes)
				(filter_ratio 0.9)
				(enabled yes)
				(allow_two_segments yes)
				(prefer_zone_connections yes)
			)
		)
		(pad "" smd custom
			(at 1.7 1.7 270)
			(size 0.62 0.62)
			(layers "F.Paste")
			(thermal_bridge_angle 90)
			(options
				(clearance outline)
				(anchor circle)
			)
			(primitives
				(gr_arc
					(start -0.250195 1.279127)
					(mid 0.285453 0.294389)
					(end 1.266786 -0.24747)
					(width 0.2)
				)
				(gr_arc
					(start -0.34334 1.279127)
					(mid 0.218448 0.232561)
					(end 1.259603 -0.339191)
					(width 0.2)
				)
				(gr_arc
					(start -0.436309 1.279127)
					(mid 0.152481 0.169693)
					(end 1.255279 -0.431435)
					(width 0.2)
				)
				(gr_arc
					(start -0.529126 1.279127)
					(mid 0.087542 0.105784)
					(end 1.253811 -0.524161)
					(width 0.2)
				)
				(gr_arc
					(start -0.621807 1.279127)
					(mid 0.0309 0.033527)
					(end 1.275473 -0.621136)
					(width 0.2)
				)
				(gr_arc
					(start -0.71437 1.279127)
					(mid -0.037758 -0.026651)
					(end 1.263664 -0.711602)
					(width 0.2)
				)
				(gr_arc
					(start -0.806826 1.279127)
					(mid -0.105837 -0.087395)
					(end 1.253435 -0.802342)
					(width 0.2)
				)
				(gr_arc
					(start -0.899187 1.279127)
					(mid -0.165236 -0.156885)
					(end 1.267475 -0.897258)
					(width 0.2)
				)
				(gr_arc
					(start -0.991463 1.279127)
					(mid -0.228522 -0.222449)
					(end 1.270645 -0.990112)
					(width 0.2)
				)
				(gr_arc
					(start -1.083663 1.279127)
					(mid -0.294507 -0.285313)
					(end 1.266278 -1.081674)
					(width 0.2)
				)
				(gr_line
					(start 1.279127 -0.250195)
					(end 1.279127 -1.083663)
					(width 0.2)
				)
				(gr_line
					(start -0.250195 1.279127)
					(end -1.083663 1.279127)
					(width 0.2)
				)
			)
			(teardrops
				(best_length_ratio 0.2)
				(max_length 1)
				(best_width_ratio 0.9)
				(max_width 2)
				(curved_edges yes)
				(filter_ratio 0.9)
				(enabled yes)
				(allow_two_segments yes)
				(prefer_zone_connections yes)
			)
		)
		(pad "1" thru_hole circle
			(at 0 0 90)
			(size 6 6)
			(drill 3.7)
			(layers "*.Cu" "*.Mask")
			(remove_unused_layers no)
			(net 1 "GND")
			(pintype "passive")
			(teardrops
				(best_length_ratio 0.4)
				(max_length 1)
				(best_width_ratio 0.9)
				(max_width 2)
				(curved_edges yes)
				(filter_ratio 0.9)
				(enabled yes)
				(allow_two_segments yes)
				(prefer_zone_connections yes)
			)
		)
	)
	(footprint "antmicro-footprints:R_0201"
		(layer "F.Cu")
		(at 153.33 147.31 90)
		(descr "Resistor SMD 0201")
		(tags "resistor SMD 0201")
		(property "Reference" "R256"
			(at -4.125 0.57 90)
			(layer "F.SilkS")
			(effects
				(font
					(size 0.7 0.7)
					(thickness 0.15)
				)
				(justify left bottom)
			)
		)
		(property "Value" "R_0R_0201"
			(at 0 1.25 90)
			(layer "F.Fab")
			(effects
				(font
					(size 0.7 0.7)
					(thickness 0.15)
				)
				(justify left bottom)
			)
		)
		(property "Datasheet" "https://www.bourns.com/docs/product-datasheets/cr.pdf"
			(at 0 0 90)
			(layer "F.Fab")
			(hide yes)
			(effects
				(font
					(size 1.27 1.27)
					(thickness 0.15)
				)
			)
		)
		(property "Author" "Antmicro"
			(at 300.64 -6.02 0)
			(layer "F.Fab")
			(hide yes)
			(effects
				(font
					(size 1 1)
					(thickness 0.15)
				)
			)
		)
		(property "License" "Apache-2.0"
			(at 300.64 -6.02 0)
			(layer "F.Fab")
			(hide yes)
			(effects
				(font
					(size 1 1)
					(thickness 0.15)
				)
			)
		)
		(property "MPN" "CR0201-FX-0R00GLF"
			(at 300.64 -6.02 0)
			(layer "F.Fab")
			(hide yes)
			(effects
				(font
					(size 1 1)
					(thickness 0.15)
				)
			)
		)
		(property "Manufacturer" "Bourns"
			(at 300.64 -6.02 0)
			(layer "F.Fab")
			(hide yes)
			(effects
				(font
					(size 1 1)
					(thickness 0.15)
				)
			)
		)
		(property "Tolerance" "1%"
			(at 300.64 -6.02 0)
			(layer "F.Fab")
			(hide yes)
			(effects
				(font
					(size 1 1)
					(thickness 0.15)
				)
			)
		)
		(property "Val" "0R"
			(at 300.64 -6.02 0)
			(layer "F.Fab")
			(hide yes)
			(effects
				(font
					(size 1 1)
					(thickness 0.15)
				)
			)
		)
		(sheetname "KR to SFI #1")
		(sheetfile "kr_sfi.kicad_sch")
		(attr smd)
		(fp_rect
			(start -0.7 -0.35)
			(end 0.7 0.35)
			(stroke
				(width 0.05)
				(type default)
			)
			(fill no)
			(layer "F.CrtYd")
		)
		(fp_rect
			(start -0.3 -0.15)
			(end 0.298 0.148)
			(stroke
				(width 0.15)
				(type solid)
			)
			(fill no)
			(layer "F.Fab")
		)
		(pad "" smd roundrect
			(at -0.346 0 90)
			(size 0.318 0.36)
			(layers "F.Paste")
			(roundrect_rratio 0.25)
			(teardrops
				(best_length_ratio 0.2)
				(max_length 1)
				(best_width_ratio 0.9)
				(max_width 2)
				(curved_edges yes)
				(filter_ratio 0.9)
				(enabled yes)
				(allow_two_segments yes)
				(prefer_zone_connections yes)
			)
		)
		(pad "" smd roundrect
			(at 0.344 0 90)
			(size 0.318 0.36)
			(layers "F.Paste")
			(roundrect_rratio 0.25)
			(teardrops
				(best_length_ratio 0.2)
				(max_length 1)
				(best_width_ratio 0.9)
				(max_width 2)
				(curved_edges yes)
				(filter_ratio 0.9)
				(enabled yes)
				(allow_two_segments yes)
				(prefer_zone_connections yes)
			)
		)
		(pad "1" smd roundrect
			(at -0.32 0 90)
			(size 0.46 0.4)
			(layers "F.Cu" "F.Mask")
			(roundrect_rratio 0.25)
			(net 432 "/2xSFP+/10GKR_SFP0.RX+")
			(pintype "passive")
			(teardrops
				(best_length_ratio 0.2)
				(max_length 1)
				(best_width_ratio 0.9)
				(max_width 2)
				(curved_edges yes)
				(filter_ratio 0.9)
				(enabled yes)
				(allow_two_segments yes)
				(prefer_zone_connections yes)
			)
		)
		(pad "2" smd roundrect
			(at 0.32 0 90)
			(size 0.46 0.4)
			(layers "F.Cu" "F.Mask")
			(roundrect_rratio 0.25)
			(net 664 "/2xSFP+/KR to SFI #1/KR_R.RX+")
			(pintype "passive")
			(teardrops
				(best_length_ratio 0.2)
				(max_length 1)
				(best_width_ratio 0.9)
				(max_width 2)
				(curved_edges yes)
				(filter_ratio 0.9)
				(enabled yes)
				(allow_two_segments yes)
				(prefer_zone_connections yes)
			)
		)
	)
	(footprint "antmicro-footprints:R_0402_1005Metric"
		(layer "F.Cu")
		(at 157.55 156.81 -90)
		(descr "Resistor SMD 0402")
		(tags "resistor SMD 0402")
		(property "Reference" "R35"
			(at -3.013 -0.449 90)
			(layer "F.SilkS")
			(effects
				(font
					(size 0.7 0.7)
					(thickness 0.15)
				)
				(justify right bottom)
			)
		)
		(property "Value" "R_0R_0402"
			(at -1.011843 1.772047 90)
			(layer "F.Fab")
			(effects
				(font
					(size 0.7 0.7)
					(thickness 0.15)
				)
				(justify right bottom)
			)
		)
		(property "Datasheet" "https://industrial.panasonic.com/cdbs/www-data/pdf/RDA0000/AOA0000C301.pdf"
			(at 0 0 270)
			(layer "F.Fab")
			(hide yes)
			(effects
				(font
					(size 1.27 1.27)
					(thickness 0.15)
				)
			)
		)
		(property "Author" "Antmicro"
			(at 0.74 314.36 0)
			(layer "F.Fab")
			(hide yes)
			(effects
				(font
					(size 1 1)
					(thickness 0.15)
				)
			)
		)
		(property "Current" "1A"
			(at 0.74 314.36 0)
			(layer "F.Fab")
			(hide yes)
			(effects
				(font
					(size 1 1)
					(thickness 0.15)
				)
			)
		)
		(property "License" "Apache-2.0"
			(at 0.74 314.36 0)
			(layer "F.Fab")
			(hide yes)
			(effects
				(font
					(size 1 1)
					(thickness 0.15)
				)
			)
		)
		(property "MPN" "ERJ2GE0R00X"
			(at 0.74 314.36 0)
			(layer "F.Fab")
			(hide yes)
			(effects
				(font
					(size 1 1)
					(thickness 0.15)
				)
			)
		)
		(property "Manufacturer" "Panasonic"
			(at 0.74 314.36 0)
			(layer "F.Fab")
			(hide yes)
			(effects
				(font
					(size 1 1)
					(thickness 0.15)
				)
			)
		)
		(property "Public" "False"
			(at 0.74 314.36 0)
			(layer "F.Fab")
			(hide yes)
			(effects
				(font
					(size 1 1)
					(thickness 0.15)
				)
			)
		)
		(property "Tolerance" ""
			(at 0.74 314.36 0)
			(layer "F.Fab")
			(hide yes)
			(effects
				(font
					(size 1 1)
					(thickness 0.15)
				)
			)
		)
		(property "Val" "0R"
			(at 0.74 314.36 0)
			(layer "F.Fab")
			(hide yes)
			(effects
				(font
					(size 1 1)
					(thickness 0.15)
				)
			)
		)
		(sheetname "2xSFP+")
		(sheetfile "2xSFP+.kicad_sch")
		(attr smd)
		(fp_rect
			(start -0.925 -0.47)
			(end 0.925 0.47)
			(stroke
				(width 0.05)
				(type default)
			)
			(fill no)
			(layer "F.CrtYd")
		)
		(fp_rect
			(start -0.5 -0.25)
			(end 0.5 0.25)
			(stroke
				(width 0.15)
				(type solid)
			)
			(fill no)
			(layer "F.Fab")
		)
		(pad "1" smd roundrect
			(at -0.48 0 270)
			(size 0.59 0.64)
			(layers "F.Cu" "F.Mask" "F.Paste")
			(roundrect_rratio 0.25)
			(net 528 "/Backplane/~{PERST}")
			(pintype "passive")
			(teardrops
				(best_length_ratio 0.2)
				(max_length 1)
				(best_width_ratio 0.9)
				(max_width 2)
				(curved_edges yes)
				(filter_ratio 0.9)
				(enabled yes)
				(allow_two_segments yes)
				(prefer_zone_connections yes)
			)
		)
		(pad "2" smd roundrect
			(at 0.48 0 270)
			(size 0.59 0.64)
			(layers "F.Cu" "F.Mask" "F.Paste")
			(roundrect_rratio 0.25)
			(net 560 "Net-(U5-~{RESET})")
			(pintype "passive")
			(teardrops
				(best_length_ratio 0.2)
				(max_length 1)
				(best_width_ratio 0.9)
				(max_width 2)
				(curved_edges yes)
				(filter_ratio 0.9)
				(enabled yes)
				(allow_two_segments yes)
				(prefer_zone_connections yes)
			)
		)
	)
	(footprint "antmicro-footprints:R_0402_1005Metric"
		(layer "F.Cu")
		(at 136.6 105.3 180)
		(descr "Resistor SMD 0402")
		(tags "resistor SMD 0402")
		(property "Reference" "R15"
			(at -1.1 -1.4 0)
			(layer "F.SilkS")
			(effects
				(font
					(size 0.7 0.7)
					(thickness 0.15)
				)
				(justify right bottom)
			)
		)
		(property "Value" "R_75R_0402"
			(at -1.011843 1.772047 0)
			(layer "F.Fab")
			(effects
				(font
					(size 0.7 0.7)
					(thickness 0.15)
				)
				(justify right bottom)
			)
		)
		(property "Datasheet" "https://www.bourns.com/docs/product-datasheets/cr.pdf"
			(at 0 0 180)
			(layer "F.Fab")
			(hide yes)
			(effects
				(font
					(size 1.27 1.27)
					(thickness 0.15)
				)
			)
		)
		(property "Author" "Antmicro"
			(at 273.2 210.6 0)
			(layer "F.Fab")
			(hide yes)
			(effects
				(font
					(size 1 1)
					(thickness 0.15)
				)
			)
		)
		(property "License" "Apache-2.0"
			(at 273.2 210.6 0)
			(layer "F.Fab")
			(hide yes)
			(effects
				(font
					(size 1 1)
					(thickness 0.15)
				)
			)
		)
		(property "MPN" "CR0402-FX-75R0GLF"
			(at 273.2 210.6 0)
			(layer "F.Fab")
			(hide yes)
			(effects
				(font
					(size 1 1)
					(thickness 0.15)
				)
			)
		)
		(property "Manufacturer" "Bourns"
			(at 273.2 210.6 0)
			(layer "F.Fab")
			(hide yes)
			(effects
				(font
					(size 1 1)
					(thickness 0.15)
				)
			)
		)
		(property "Public" "False"
			(at 273.2 210.6 0)
			(layer "F.Fab")
			(hide yes)
			(effects
				(font
					(size 1 1)
					(thickness 0.15)
				)
			)
		)
		(property "Tolerance" "1%"
			(at 273.2 210.6 0)
			(layer "F.Fab")
			(hide yes)
			(effects
				(font
					(size 1 1)
					(thickness 0.15)
				)
			)
		)
		(property "Val" "75R"
			(at 273.2 210.6 0)
			(layer "F.Fab")
			(hide yes)
			(effects
				(font
					(size 1 1)
					(thickness 0.15)
				)
			)
		)
		(sheetname "2xUSB3.0+RJ45")
		(sheetfile "usb3+rj45.kicad_sch")
		(attr smd)
		(fp_rect
			(start -0.925 -0.47)
			(end 0.925 0.47)
			(stroke
				(width 0.05)
				(type default)
			)
			(fill no)
			(layer "F.CrtYd")
		)
		(fp_rect
			(start -0.5 -0.25)
			(end 0.5 0.25)
			(stroke
				(width 0.15)
				(type solid)
			)
			(fill no)
			(layer "F.Fab")
		)
		(pad "1" smd roundrect
			(at -0.48 0 180)
			(size 0.59 0.64)
			(layers "F.Cu" "F.Mask" "F.Paste")
			(roundrect_rratio 0.25)
			(net 50 "Net-(C12-Pad2)")
			(pintype "passive")
			(teardrops
				(best_length_ratio 0.2)
				(max_length 1)
				(best_width_ratio 0.9)
				(max_width 2)
				(curved_edges yes)
				(filter_ratio 0.9)
				(enabled yes)
				(allow_two_segments yes)
				(prefer_zone_connections yes)
			)
		)
		(pad "2" smd roundrect
			(at 0.48 0 180)
			(size 0.59 0.64)
			(layers "F.Cu" "F.Mask" "F.Paste")
			(roundrect_rratio 0.25)
			(net 550 "Net-(R15-Pad2)")
			(pintype "passive")
			(teardrops
				(best_length_ratio 0.2)
				(max_length 1)
				(best_width_ratio 0.9)
				(max_width 2)
				(curved_edges yes)
				(filter_ratio 0.9)
				(enabled yes)
				(allow_two_segments yes)
				(prefer_zone_connections yes)
			)
		)
	)
)
